# TIMECARD (Time Appliance Project (Time Card)) — schematic netlist excerpt (pin names and nets, part order shuffled) for the footprints in the layout excerpt that follows; sources: Cadence DE-HDL packaged netlist, KiCad conversion of R4006-B0001-02_R01.brd

C18  CAPACITOR  0.1UF 10V 10%  pkg SMC_0402R_H022  page 28 : \1\ = XP3R3V ; \2\ = SG
TP3  TP_PIONT  pkg TP010CT020B030_PTH  page 25 : \1\ = XP3R3V_FT4232

(kicad_pcb
	(version 20260206)
	(generator "pcbnew")
	(generator_version "10.0")
	(general
		(thickness 1.6)
		(legacy_teardrops no)
	)
	(paper "A4")
	(title_block
		(title "timecard-production-celestica-r4006 — R4006-B0001-02_R01.brd")
		(comment 1 "Time Appliance Project (Time Card) / footprints 531-532 of 1113")
	)
	(layers
		(0 "F.Cu" signal "TOP")
		(4 "In1.Cu" signal "L02_GND1")
		(6 "In2.Cu" signal "L03_SIG1")
		(8 "In3.Cu" signal "L04_GND2")
		(10 "In4.Cu" signal "L05_VCC1")
		(12 "In5.Cu" signal "L06_VCC2")
		(14 "In6.Cu" signal "L07_GND3")
		(16 "In7.Cu" signal "L08_SIG2")
		(18 "In8.Cu" signal "L09_GND4")
		(2 "B.Cu" signal "BOTTOM")
		(9 "F.Adhes" user "F.Adhesive")
		(11 "B.Adhes" user "B.Adhesive")
		(13 "F.Paste" user "Package Geometry/Pastemask Top")
		(15 "B.Paste" user "Package Geometry/Pastemask Bottom")
		(5 "F.SilkS" user "Ref Des/Silkscreen Top")
		(7 "B.SilkS" user "Ref Des/Silkscreen Bottom")
		(1 "F.Mask" user "Board Geometry/Soldermask Top")
		(3 "B.Mask" user "Board Geometry/Soldermask Bottom")
		(17 "Dwgs.User" user "User.Drawings")
		(19 "Cmts.User" user "User.Comments")
		(21 "Eco1.User" user "User.Eco1")
		(23 "Eco2.User" user "User.Eco2")
		(25 "Edge.Cuts" user "Board Geometry/Outline")
		(27 "Margin" user)
		(31 "F.CrtYd" user "Package Geometry/Place Bound Top")
		(29 "B.CrtYd" user "Package Geometry/Place Bound Bottom")
		(35 "F.Fab" user "Ref Des/Assembly Top")
		(33 "B.Fab" user "Ref Des/Assembly Bottom")
	)
	(footprint ""
		(layer "F.Cu")
		(at 82.677 -93.599 90)
		(property "Reference" "C18"
			(at -3.81 -3.38963 90)
			(unlocked yes)
			(layer "F.SilkS")
			(effects
				(font
					(size 0.7874 0.5842)
					(thickness 0.1524)
				)
			)
		)
		(property "Value" "VAL*"
			(at 0.0762 2.067306 90)
			(unlocked yes)
			(layer "F.Fab")
			(hide yes)
			(effects
				(font
					(size 0.7874 0.5842)
					(thickness 0.1524)
				)
			)
		)
		(property "Tolerance" "TOL*"
			(at 0.0762 3.032506 90)
			(unlocked yes)
			(layer "Cmts.User")
			(hide yes)
			(effects
				(font
					(size 0.7874 0.5842)
					(thickness 0.1524)
				)
			)
		)
		(property "User Part Number" "PARTNUM*"
			(at 0.1016 4.023106 90)
			(unlocked yes)
			(layer "Cmts.User")
			(hide yes)
			(effects
				(font
					(size 0.7874 0.5842)
					(thickness 0.1524)
				)
			)
		)
		(property "Device Type" "CAPACITOR-G105-0B104-CK,0.1UF,A"
			(at 0.0508 1.127506 90)
			(unlocked yes)
			(layer "F.Fab")
			(hide yes)
			(effects
				(font
					(size 0.7874 0.5842)
					(thickness 0.1524)
				)
			)
		)
		(duplicate_pad_numbers_are_jumpers no)
		(fp_line
			(start 1.143 -0.5588)
			(end -1.143 -0.5588)
			(stroke
				(width 0.1)
				(type default)
			)
			(layer "F.SilkS")
		)
		(fp_line
			(start -1.143 -0.5588)
			(end -1.143 0.5588)
			(stroke
				(width 0.1)
				(type default)
			)
			(layer "F.SilkS")
		)
		(fp_line
			(start 1.143 0.5588)
			(end 1.143 -0.5588)
			(stroke
				(width 0.1)
				(type default)
			)
			(layer "F.SilkS")
		)
		(fp_line
			(start -1.143 0.5588)
			(end 1.143 0.5588)
			(stroke
				(width 0.1)
				(type default)
			)
			(layer "F.SilkS")
		)
		(fp_rect
			(start -1.143 -0.5588)
			(end 1.143 0.5588)
			(stroke
				(width 0)
				(type default)
			)
			(fill no)
			(layer "F.CrtYd")
		)
		(fp_line
			(start 0.508 -0.3048)
			(end -0.508 -0.3048)
			(stroke
				(width 0.1)
				(type default)
			)
			(layer "F.Fab")
		)
		(fp_line
			(start -0.508 -0.3048)
			(end -0.508 0.3048)
			(stroke
				(width 0.1)
				(type default)
			)
			(layer "F.Fab")
		)
		(fp_line
			(start 0.508 0.3048)
			(end 0.508 -0.3048)
			(stroke
				(width 0.1)
				(type default)
			)
			(layer "F.Fab")
		)
		(fp_line
			(start -0.508 0.3048)
			(end 0.508 0.3048)
			(stroke
				(width 0.1)
				(type default)
			)
			(layer "F.Fab")
		)
		(pad "1" smd rect
			(at -0.5334 0 90)
			(size 0.7112 0.6096)
			(layers "F.Cu" "F.Mask" "F.Paste")
			(net "XP3R3V")
		)
		(pad "2" smd rect
			(at 0.5334 0 90)
			(size 0.7112 0.6096)
			(layers "F.Cu" "F.Mask" "F.Paste")
			(net "SG")
		)
		(zone
			(layer "F.Cu")
			(hatch none 0.5)
			(connect_pads
				(clearance 0)
			)
			(min_thickness 0.25)
			(keepout
				(tracks allowed)
				(vias not_allowed)
				(pads allowed)
				(copperpour not_allowed)
				(footprints allowed)
			)
			(placement
				(enabled no)
				(sheetname "")
			)
			(fill
				(thermal_gap 0.5)
				(thermal_bridge_width 0.5)
				(island_removal_mode 0)
			)
			(polygon
				(pts
					(xy 82.3722 -93.5228) (xy 82.9818 -93.5228) (xy 82.9818 -93.6752) (xy 82.3722 -93.6752)
				)
			)
		)
	)
	(footprint ""
		(layer "F.Cu")
		(at 38.989 -78.867 -90)
		(property "Reference" "TP3"
			(at 0 0 270)
			(layer "F.SilkS")
			(hide yes)
			(effects
				(font
					(size 1.27 1.27)
				)
			)
		)
		(property "Value" ""
			(at 0 0 270)
			(layer "F.Fab")
			(effects
				(font
					(size 1.27 1.27)
				)
			)
		)
		(property "Device Type" "TP_PIONT-TP010CT020B030_PTH-TPA"
			(at -1.341882 0.996696 270)
			(unlocked yes)
			(layer "F.Fab")
			(hide yes)
			(effects
				(font
					(size 0.7874 0.5842)
					(thickness 0.1524)
				)
				(justify left)
			)
		)
		(duplicate_pad_numbers_are_jumpers no)
		(fp_poly
			(pts
				(arc
					(start 0 -0.889)
					(mid 0 0.889)
					(end 0 -0.889)
				)
			)
			(stroke
				(width 0)
				(type default)
			)
			(fill no)
			(layer "B.CrtYd")
		)
		(fp_poly
			(pts
				(arc
					(start 0 -0.889)
					(mid 0 0.889)
					(end 0 -0.889)
				)
			)
			(stroke
				(width 0)
				(type default)
			)
			(fill no)
			(layer "F.CrtYd")
		)
		(pad "1" thru_hole circle
			(at 0 0 270)
			(size 0.508 0.508)
			(drill 0.254)
			(layers "*.Cu" "*.Mask")
			(remove_unused_layers no)
			(net "XP3R3V_FT4232")
			(clearance 0.1016)
			(padstack
				(mode front_inner_back)
				(layer "Inner"
					(shape circle)
					(size 0.508 0.508)
					(clearance 0.1016)
				)
				(layer "B.Cu"
					(shape circle)
					(size 0.762 0.762)
					(clearance -0.0254)
				)
			)
		)
	)
)
